# TIMECARD (Time Appliance Project (Time Card)) — schematic netlist excerpt (pin names and nets, part order shuffled) for the footprints in the layout excerpt that follows; sources: Cadence DE-HDL packaged netlist, KiCad conversion of R4006-B0001-02_R01.brd

R404  RESISTOR  10KOHM 1%  pkg SMC_0402R_H016  page 10 : \1\ = XP3R3V_FPGA ; \2\ = FPGA_TMS
R463  RESISTOR  12KOHM 1%  pkg SMC_0402R  page 24 : \1\ = UNNAMED_524_FT4232HLREELQFP64_6 ; \2\ = SG

(kicad_pcb
	(version 20260206)
	(generator "pcbnew")
	(generator_version "10.0")
	(general
		(thickness 1.6)
		(legacy_teardrops no)
	)
	(paper "A4")
	(title_block
		(title "timecard-production-celestica-r4006 — R4006-B0001-02_R01.brd")
		(comment 1 "Time Appliance Project (Time Card) / footprints 863-864 of 1113")
	)
	(layers
		(0 "F.Cu" signal "TOP")
		(4 "In1.Cu" signal "L02_GND1")
		(6 "In2.Cu" signal "L03_SIG1")
		(8 "In3.Cu" signal "L04_GND2")
		(10 "In4.Cu" signal "L05_VCC1")
		(12 "In5.Cu" signal "L06_VCC2")
		(14 "In6.Cu" signal "L07_GND3")
		(16 "In7.Cu" signal "L08_SIG2")
		(18 "In8.Cu" signal "L09_GND4")
		(2 "B.Cu" signal "BOTTOM")
		(9 "F.Adhes" user "F.Adhesive")
		(11 "B.Adhes" user "B.Adhesive")
		(13 "F.Paste" user "Package Geometry/Pastemask Top")
		(15 "B.Paste" user "Package Geometry/Pastemask Bottom")
		(5 "F.SilkS" user "Ref Des/Silkscreen Top")
		(7 "B.SilkS" user "Ref Des/Silkscreen Bottom")
		(1 "F.Mask" user "Board Geometry/Soldermask Top")
		(3 "B.Mask" user "Board Geometry/Soldermask Bottom")
		(17 "Dwgs.User" user "User.Drawings")
		(19 "Cmts.User" user "User.Comments")
		(21 "Eco1.User" user "User.Eco1")
		(23 "Eco2.User" user "User.Eco2")
		(25 "Edge.Cuts" user "Board Geometry/Outline")
		(27 "Margin" user)
		(31 "F.CrtYd" user "Package Geometry/Place Bound Top")
		(29 "B.CrtYd" user "Package Geometry/Place Bound Bottom")
		(35 "F.Fab" user "Ref Des/Assembly Top")
		(33 "B.Fab" user "Ref Des/Assembly Bottom")
	)
	(footprint ""
		(layer "B.Cu")
		(at 138.4808 -74.7649 90)
		(property "Reference" "R404"
			(at -0.38227 -3.4798 0)
			(unlocked yes)
			(layer "B.SilkS")
			(effects
				(font
					(size 0.7874 0.5842)
					(thickness 0.1524)
				)
				(justify mirror)
			)
		)
		(property "Value" "VAL*"
			(at -0.02032 2.13233 90)
			(unlocked yes)
			(layer "B.Fab")
			(hide yes)
			(effects
				(font
					(size 0.7874 0.5842)
					(thickness 0.1524)
				)
				(justify mirror)
			)
		)
		(property "Device Type" "RESISTOR-G155-11002-01,10KOHM,A"
			(at -0.008382 1.210564 90)
			(unlocked yes)
			(layer "B.Fab")
			(hide yes)
			(effects
				(font
					(size 0.7874 0.5842)
					(thickness 0.1524)
				)
				(justify mirror)
			)
		)
		(property "User Part Number" "PARTNUM*"
			(at -0.02032 4.024884 90)
			(unlocked yes)
			(layer "Cmts.User")
			(hide yes)
			(effects
				(font
					(size 0.7874 0.5842)
					(thickness 0.1524)
				)
				(justify mirror)
			)
		)
		(property "Tolerance" "TOL*"
			(at -0.044704 3.05435 90)
			(unlocked yes)
			(layer "Cmts.User")
			(hide yes)
			(effects
				(font
					(size 0.7874 0.5842)
					(thickness 0.1524)
				)
				(justify mirror)
			)
		)
		(duplicate_pad_numbers_are_jumpers no)
		(fp_line
			(start 1.143 -0.5588)
			(end 1.143 0.5588)
			(stroke
				(width 0.1)
				(type default)
			)
			(layer "B.SilkS")
		)
		(fp_line
			(start -1.143 -0.5588)
			(end 1.143 -0.5588)
			(stroke
				(width 0.1)
				(type default)
			)
			(layer "B.SilkS")
		)
		(fp_line
			(start 1.143 0.5588)
			(end -1.143 0.5588)
			(stroke
				(width 0.1)
				(type default)
			)
			(layer "B.SilkS")
		)
		(fp_line
			(start -1.143 0.5588)
			(end -1.143 -0.5588)
			(stroke
				(width 0.1)
				(type default)
			)
			(layer "B.SilkS")
		)
		(fp_rect
			(start 1.143 0.5588)
			(end -1.143 -0.5588)
			(stroke
				(width 0)
				(type default)
			)
			(fill no)
			(layer "B.CrtYd")
		)
		(fp_line
			(start 0.508 -0.3048)
			(end 0.508 0.3048)
			(stroke
				(width 0.1)
				(type default)
			)
			(layer "B.Fab")
		)
		(fp_line
			(start -0.508 -0.3048)
			(end 0.508 -0.3048)
			(stroke
				(width 0.1)
				(type default)
			)
			(layer "B.Fab")
		)
		(fp_line
			(start 0.508 0.3048)
			(end -0.508 0.3048)
			(stroke
				(width 0.1)
				(type default)
			)
			(layer "B.Fab")
		)
		(fp_line
			(start -0.508 0.3048)
			(end -0.508 -0.3048)
			(stroke
				(width 0.1)
				(type default)
			)
			(layer "B.Fab")
		)
		(pad "1" smd rect
			(at 0.5334 0 270)
			(size 0.7112 0.6096)
			(layers "B.Cu" "B.Mask" "B.Paste")
			(net "XP3R3V_FPGA")
		)
		(pad "2" smd rect
			(at -0.5334 0 270)
			(size 0.7112 0.6096)
			(layers "B.Cu" "B.Mask" "B.Paste")
			(net "FPGA_TMS")
		)
		(zone
			(layer "B.Cu")
			(hatch none 0.5)
			(connect_pads
				(clearance 0)
			)
			(min_thickness 0.25)
			(keepout
				(tracks not_allowed)
				(vias allowed)
				(pads allowed)
				(copperpour not_allowed)
				(footprints allowed)
			)
			(placement
				(enabled no)
				(sheetname "")
			)
			(fill
				(thermal_gap 0.5)
				(thermal_bridge_width 0.5)
				(island_removal_mode 0)
			)
			(polygon
				(pts
					(xy 138.7856 -74.8411) (xy 138.176 -74.8411) (xy 138.176 -74.6887) (xy 138.7856 -74.6887)
				)
			)
		)
		(zone
			(layer "B.Cu")
			(hatch none 0.5)
			(connect_pads
				(clearance 0)
			)
			(min_thickness 0.25)
			(keepout
				(tracks allowed)
				(vias not_allowed)
				(pads allowed)
				(copperpour not_allowed)
				(footprints allowed)
			)
			(placement
				(enabled no)
				(sheetname "")
			)
			(fill
				(thermal_gap 0.5)
				(thermal_bridge_width 0.5)
				(island_removal_mode 0)
			)
			(polygon
				(pts
					(xy 138.7856 -74.8411) (xy 138.176 -74.8411) (xy 138.176 -74.6887) (xy 138.7856 -74.6887)
				)
			)
		)
	)
	(footprint ""
		(layer "B.Cu")
		(at 29.845 -91.059 -90)
		(property "Reference" "R463"
			(at -3.175 0.03937 270)
			(unlocked yes)
			(layer "B.SilkS")
			(effects
				(font
					(size 0.7874 0.5842)
					(thickness 0.1524)
				)
				(justify mirror)
			)
		)
		(property "Value" "VAL*"
			(at -0.0508 2.245106 270)
			(unlocked yes)
			(layer "B.Fab")
			(hide yes)
			(effects
				(font
					(size 0.7874 0.5842)
					(thickness 0.1524)
				)
				(justify mirror)
			)
		)
		(property "User Part Number" "PARTNUM*"
			(at -0.0762 4.302506 270)
			(unlocked yes)
			(layer "Cmts.User")
			(hide yes)
			(effects
				(font
					(size 0.7874 0.5842)
					(thickness 0.1524)
				)
				(justify mirror)
			)
		)
		(property "Device Type" "RESISTOR-G155-01202-01,12KOHM,A"
			(at -0.0762 1.254506 270)
			(unlocked yes)
			(layer "B.Fab")
			(hide yes)
			(effects
				(font
					(size 0.7874 0.5842)
					(thickness 0.1524)
				)
				(justify mirror)
			)
		)
		(property "Tolerance" "TOL*"
			(at -0.0508 3.261106 270)
			(unlocked yes)
			(layer "Cmts.User")
			(hide yes)
			(effects
				(font
					(size 0.7874 0.5842)
					(thickness 0.1524)
				)
				(justify mirror)
			)
		)
		(duplicate_pad_numbers_are_jumpers no)
		(fp_line
			(start -1.143 0.5588)
			(end -1.143 -0.5588)
			(stroke
				(width 0.1)
				(type default)
			)
			(layer "B.SilkS")
		)
		(fp_line
			(start 1.143 0.5588)
			(end -1.143 0.5588)
			(stroke
				(width 0.1)
				(type default)
			)
			(layer "B.SilkS")
		)
		(fp_line
			(start -1.143 -0.5588)
			(end 1.143 -0.5588)
			(stroke
				(width 0.1)
				(type default)
			)
			(layer "B.SilkS")
		)
		(fp_line
			(start 1.143 -0.5588)
			(end 1.143 0.5588)
			(stroke
				(width 0.1)
				(type default)
			)
			(layer "B.SilkS")
		)
		(fp_poly
			(pts
				(xy 1.143 0.5588) (xy -1.143 0.5588) (xy -1.143 -0.5588) (xy 1.143 -0.5588)
			)
			(stroke
				(width 0)
				(type default)
			)
			(fill no)
			(layer "B.CrtYd")
		)
		(fp_line
			(start -0.508 0.3048)
			(end -0.508 -0.3048)
			(stroke
				(width 0.1)
				(type default)
			)
			(layer "B.Fab")
		)
		(fp_line
			(start 0.508 0.3048)
			(end -0.508 0.3048)
			(stroke
				(width 0.1)
				(type default)
			)
			(layer "B.Fab")
		)
		(fp_line
			(start -0.508 -0.3048)
			(end 0.508 -0.3048)
			(stroke
				(width 0.1)
				(type default)
			)
			(layer "B.Fab")
		)
		(fp_line
			(start 0.508 -0.3048)
			(end 0.508 0.3048)
			(stroke
				(width 0.1)
				(type default)
			)
			(layer "B.Fab")
		)
		(pad "1" smd rect
			(at 0.5334 0 90)
			(size 0.7112 0.6096)
			(layers "B.Cu" "B.Mask" "B.Paste")
			(net "UNNAMED_524_FT4232HLREELQFP64_6")
		)
		(pad "2" smd rect
			(at -0.5334 0 90)
			(size 0.7112 0.6096)
			(layers "B.Cu" "B.Mask" "B.Paste")
			(net "SG")
		)
		(zone
			(layer "B.Cu")
			(hatch none 0.5)
			(connect_pads
				(clearance 0)
			)
			(min_thickness 0.25)
			(keepout
				(tracks allowed)
				(vias not_allowed)
				(pads allowed)
				(copperpour not_allowed)
				(footprints allowed)
			)
			(placement
				(enabled no)
				(sheetname "")
			)
			(fill
				(thermal_gap 0.5)
				(thermal_bridge_width 0.5)
				(island_removal_mode 0)
			)
			(polygon
				(pts
					(xy 29.5402 -90.9828) (xy 30.1498 -90.9828) (xy 30.1498 -91.1352) (xy 29.5402 -91.1352)
				)
			)
		)
		(zone
			(layer "B.Cu")
			(hatch none 0.5)
			(connect_pads
				(clearance 0)
			)
			(min_thickness 0.25)
			(keepout
				(tracks not_allowed)
				(vias allowed)
				(pads allowed)
				(copperpour not_allowed)
				(footprints allowed)
			)
			(placement
				(enabled no)
				(sheetname "")
			)
			(fill
				(thermal_gap 0.5)
				(thermal_bridge_width 0.5)
				(island_removal_mode 0)
			)
			(polygon
				(pts
					(xy 29.5402 -90.9828) (xy 30.1498 -90.9828) (xy 30.1498 -91.1352) (xy 29.5402 -91.1352)
				)
			)
		)
	)
)
